# BASEBOARD_FAB2 (Tioga Pass) — schematic netlist excerpt (pin names and nets, part order shuffled) for the footprints in the layout excerpt that follows; sources: Cadence DE-HDL packaged netlist, KiCad conversion of Wiwynn_Tioga_Pass_MB.brd

C5G104  CAP_A  22.0UF 4V 20% X6S  pkg 0603V  page 243 : A = PVDDQ_KLM ; B = GND
C2T1  CAP_A  0.1UF 16V 10% X7R  pkg 0402V  page 154 : A = P3V3_STBY ; B = GND
CN8F1  CAP_A  1.0UF 6.3V 10% X6S  pkg 0402V  page 246 : A = P3V3_STBY ; B = GND

(kicad_pcb
	(version 20260206)
	(generator "pcbnew")
	(generator_version "10.0")
	(general
		(thickness 1.6)
		(legacy_teardrops no)
	)
	(paper "A4")
	(title_block
		(title "Wiwynn_Tioga_Pass_MB.brd")
		(comment 1 "Tioga Pass / footprints 2382-2384 of 4770")
	)
	(layers
		(0 "F.Cu" signal "TOP")
		(4 "In1.Cu" signal "L2GND")
		(6 "In2.Cu" signal "L3")
		(8 "In3.Cu" signal "L4GND")
		(10 "In4.Cu" signal "L5")
		(12 "In5.Cu" signal "L6GND")
		(14 "In6.Cu" signal "L7VCC")
		(16 "In7.Cu" signal "L8VCC")
		(18 "In8.Cu" signal "L9GND")
		(20 "In9.Cu" signal "L10")
		(22 "In10.Cu" signal "L11GND")
		(24 "In11.Cu" signal "L12")
		(26 "In12.Cu" signal "L13GND")
		(2 "B.Cu" signal "BOTTOM")
		(9 "F.Adhes" user "F.Adhesive")
		(11 "B.Adhes" user "B.Adhesive")
		(13 "F.Paste" user "Package Geometry/Pastemask Top")
		(15 "B.Paste" user "Package Geometry/Pastemask Bottom")
		(5 "F.SilkS" user "Ref Des/Silkscreen Top")
		(7 "B.SilkS" user "Ref Des/Silkscreen Bottom")
		(1 "F.Mask" user "Board Geometry/Soldermask Top")
		(3 "B.Mask" user "Board Geometry/Soldermask Bottom")
		(17 "Dwgs.User" user "User.Drawings")
		(19 "Cmts.User" user "User.Comments")
		(21 "Eco1.User" user "User.Eco1")
		(23 "Eco2.User" user "User.Eco2")
		(25 "Edge.Cuts" user "Board Geometry/Outline")
		(27 "Margin" user)
		(31 "F.CrtYd" user "Package Geometry/Place Bound Top")
		(29 "B.CrtYd" user "Package Geometry/Place Bound Bottom")
		(35 "F.Fab" user "Ref Des/Assembly Top")
		(33 "B.Fab" user "Ref Des/Assembly Bottom")
	)
	(footprint ""
		(layer "B.Cu")
		(at 107.8611 -149.8092 90)
		(property "Reference" "C5G104"
			(at -1.14681 0.76708 180)
			(unlocked yes)
			(layer "B.SilkS")
			(effects
				(font
					(size 0.7874 0.5842)
					(thickness 0.1524)
				)
				(justify mirror)
			)
		)
		(property "Value" ""
			(at 0 0 90)
			(layer "B.Fab")
			(effects
				(font
					(size 1.27 1.27)
				)
				(justify mirror)
			)
		)
		(duplicate_pad_numbers_are_jumpers no)
		(fp_rect
			(start -0.4953 -0.2032)
			(end 0.4953 1.6002)
			(stroke
				(width 0)
				(type default)
			)
			(fill no)
			(layer "B.CrtYd")
		)
		(fp_line
			(start 0.4953 -0.2032)
			(end -0.4953 -0.2032)
			(stroke
				(width 0.1)
				(type default)
			)
			(layer "B.Fab")
		)
		(fp_line
			(start -0.4953 -0.2032)
			(end -0.4953 1.6002)
			(stroke
				(width 0.1)
				(type default)
			)
			(layer "B.Fab")
		)
		(fp_line
			(start 0.4953 1.6002)
			(end 0.4953 -0.2032)
			(stroke
				(width 0.1)
				(type default)
			)
			(layer "B.Fab")
		)
		(fp_line
			(start -0.4953 1.6002)
			(end 0.4953 1.6002)
			(stroke
				(width 0.1)
				(type default)
			)
			(layer "B.Fab")
		)
		(pad "1" smd rect
			(at 0 0 270)
			(size 0.762 0.889)
			(layers "B.Cu" "B.Mask" "B.Paste")
			(net "PVDDQ_KLM")
		)
		(pad "2" smd rect
			(at 0 1.397 270)
			(size 0.762 0.889)
			(layers "B.Cu" "B.Mask" "B.Paste")
			(net "GND")
		)
		(zone
			(layer "B.Cu")
			(hatch none 0.5)
			(connect_pads
				(clearance 0)
			)
			(min_thickness 0.25)
			(keepout
				(tracks not_allowed)
				(vias allowed)
				(pads allowed)
				(copperpour not_allowed)
				(footprints allowed)
			)
			(placement
				(enabled no)
				(sheetname "")
			)
			(fill
				(thermal_gap 0.5)
				(thermal_bridge_width 0.5)
				(island_removal_mode 0)
			)
			(polygon
				(pts
					(xy 108.3056 -149.4282) (xy 108.8136 -149.4282) (xy 108.8136 -150.1902) (xy 108.3056 -150.1902)
				)
			)
		)
	)
	(footprint ""
		(layer "B.Cu")
		(at 375.519696 -62.277752)
		(property "Reference" "C2T1"
			(at 0 0 0)
			(layer "B.SilkS")
			(hide yes)
			(effects
				(font
					(size 1.27 1.27)
				)
				(justify mirror)
			)
		)
		(property "Value" ""
			(at 0 0 0)
			(layer "B.Fab")
			(effects
				(font
					(size 1.27 1.27)
				)
				(justify mirror)
			)
		)
		(duplicate_pad_numbers_are_jumpers no)
		(fp_poly
			(pts
				(xy -0.3048 -0.1016) (xy -0.3048 0.9906) (xy 0.3048 0.9906) (xy 0.3048 -0.1016)
			)
			(stroke
				(width 0)
				(type default)
			)
			(fill no)
			(layer "B.CrtYd")
		)
		(fp_line
			(start -0.3048 -0.1016)
			(end 0.3048 -0.1016)
			(stroke
				(width 0.1)
				(type default)
			)
			(layer "B.Fab")
		)
		(fp_line
			(start -0.3048 0.9906)
			(end -0.3048 -0.1016)
			(stroke
				(width 0.1)
				(type default)
			)
			(layer "B.Fab")
		)
		(fp_line
			(start 0.3048 -0.1016)
			(end 0.3048 0.9906)
			(stroke
				(width 0.1)
				(type default)
			)
			(layer "B.Fab")
		)
		(fp_line
			(start 0.3048 0.9906)
			(end -0.3048 0.9906)
			(stroke
				(width 0.1)
				(type default)
			)
			(layer "B.Fab")
		)
		(pad "1" smd rect
			(at 0 0 180)
			(size 0.508 0.508)
			(layers "B.Cu" "B.Mask" "B.Paste")
			(net "P3V3_STBY")
		)
		(pad "2" smd rect
			(at 0 0.889 180)
			(size 0.508 0.508)
			(layers "B.Cu" "B.Mask" "B.Paste")
			(net "GND")
		)
		(zone
			(layer "B.Cu")
			(hatch none 0.5)
			(connect_pads
				(clearance 0)
			)
			(min_thickness 0.25)
			(keepout
				(tracks allowed)
				(vias not_allowed)
				(pads allowed)
				(copperpour not_allowed)
				(footprints allowed)
			)
			(placement
				(enabled no)
				(sheetname "")
			)
			(fill
				(thermal_gap 0.5)
				(thermal_bridge_width 0.5)
				(island_removal_mode 0)
			)
			(polygon
				(pts
					(xy 375.773696 -62.023752) (xy 375.265696 -62.023752) (xy 375.265696 -61.642752) (xy 375.773696 -61.642752)
				)
			)
		)
		(zone
			(layer "B.Cu")
			(hatch none 0.5)
			(connect_pads
				(clearance 0)
			)
			(min_thickness 0.25)
			(keepout
				(tracks not_allowed)
				(vias allowed)
				(pads allowed)
				(copperpour not_allowed)
				(footprints allowed)
			)
			(placement
				(enabled no)
				(sheetname "")
			)
			(fill
				(thermal_gap 0.5)
				(thermal_bridge_width 0.5)
				(island_removal_mode 0)
			)
			(polygon
				(pts
					(xy 375.773696 -61.642752) (xy 375.265696 -61.642752) (xy 375.265696 -62.023752) (xy 375.773696 -62.023752)
				)
			)
		)
	)
	(footprint ""
		(layer "B.Cu")
		(at 379.476 -20.193 90)
		(property "Reference" "CN8F1"
			(at 0.8382 -0.67818 90)
			(unlocked yes)
			(layer "B.SilkS")
			(effects
				(font
					(size 0.4064 0.254)
					(thickness 0.1524)
				)
				(justify left mirror)
			)
		)
		(property "Value" ""
			(at 0 0 90)
			(layer "B.Fab")
			(effects
				(font
					(size 1.27 1.27)
				)
				(justify mirror)
			)
		)
		(duplicate_pad_numbers_are_jumpers no)
		(fp_poly
			(pts
				(xy -0.3048 -0.1016) (xy -0.3048 0.9906) (xy 0.3048 0.9906) (xy 0.3048 -0.1016)
			)
			(stroke
				(width 0)
				(type default)
			)
			(fill no)
			(layer "B.CrtYd")
		)
		(fp_line
			(start 0.3048 -0.1016)
			(end 0.3048 0.9906)
			(stroke
				(width 0.1)
				(type default)
			)
			(layer "B.Fab")
		)
		(fp_line
			(start -0.3048 -0.1016)
			(end 0.3048 -0.1016)
			(stroke
				(width 0.1)
				(type default)
			)
			(layer "B.Fab")
		)
		(fp_line
			(start 0.3048 0.9906)
			(end -0.3048 0.9906)
			(stroke
				(width 0.1)
				(type default)
			)
			(layer "B.Fab")
		)
		(fp_line
			(start -0.3048 0.9906)
			(end -0.3048 -0.1016)
			(stroke
				(width 0.1)
				(type default)
			)
			(layer "B.Fab")
		)
		(pad "1" smd rect
			(at 0 0 270)
			(size 0.508 0.508)
			(layers "B.Cu" "B.Mask" "B.Paste")
			(net "P3V3_STBY")
		)
		(pad "2" smd rect
			(at 0 0.889 270)
			(size 0.508 0.508)
			(layers "B.Cu" "B.Mask" "B.Paste")
			(net "GND")
		)
		(zone
			(layer "B.Cu")
			(hatch none 0.5)
			(connect_pads
				(clearance 0)
			)
			(min_thickness 0.25)
			(keepout
				(tracks allowed)
				(vias not_allowed)
				(pads allowed)
				(copperpour not_allowed)
				(footprints allowed)
			)
			(placement
				(enabled no)
				(sheetname "")
			)
			(fill
				(thermal_gap 0.5)
				(thermal_bridge_width 0.5)
				(island_removal_mode 0)
			)
			(polygon
				(pts
					(xy 379.73 -20.447) (xy 379.73 -19.939) (xy 380.111 -19.939) (xy 380.111 -20.447)
				)
			)
		)
		(zone
			(layer "B.Cu")
			(hatch none 0.5)
			(connect_pads
				(clearance 0)
			)
			(min_thickness 0.25)
			(keepout
				(tracks not_allowed)
				(vias allowed)
				(pads allowed)
				(copperpour not_allowed)
				(footprints allowed)
			)
			(placement
				(enabled no)
				(sheetname "")
			)
			(fill
				(thermal_gap 0.5)
				(thermal_bridge_width 0.5)
				(island_removal_mode 0)
			)
			(polygon
				(pts
					(xy 380.111 -20.447) (xy 380.111 -19.939) (xy 379.73 -19.939) (xy 379.73 -20.447)
				)
			)
		)
	)
)
